(kicad_pcb
	(version 20260206)
	(generator "pcbnew")
	(generator_version "10.0")
	(general
		(thickness 1.6)
		(legacy_teardrops no)
	)
	(paper "A4")
	(title_block
		(title "baseboard — 13948-1b.1110WZS1818.brd")
		(comment 1 "Honey Badger (Wiwynn) / footprints 1117-1125 of 2523")
	)
	(layers
		(0 "F.Cu" signal "TOP")
		(4 "In1.Cu" signal "L2GND")
		(6 "In2.Cu" signal "L3")
		(8 "In3.Cu" signal "L4VCC")
		(10 "In4.Cu" signal "L5VCC")
		(12 "In5.Cu" signal "L6")
		(14 "In6.Cu" signal "L7GND")
		(2 "B.Cu" signal "BOTTOM")
		(9 "F.Adhes" user "F.Adhesive")
		(11 "B.Adhes" user "B.Adhesive")
		(13 "F.Paste" user "Package Geometry/Pastemask Top")
		(15 "B.Paste" user "Package Geometry/Pastemask Bottom")
		(5 "F.SilkS" user "Ref Des/Silkscreen Top")
		(7 "B.SilkS" user "Ref Des/Silkscreen Bottom")
		(1 "F.Mask" user "Board Geometry/Soldermask Top")
		(3 "B.Mask" user "Board Geometry/Soldermask Bottom")
		(17 "Dwgs.User" user "User.Drawings")
		(19 "Cmts.User" user "User.Comments")
		(21 "Eco1.User" user "User.Eco1")
		(23 "Eco2.User" user "User.Eco2")
		(25 "Edge.Cuts" user "Board Geometry/Outline")
		(27 "Margin" user)
		(31 "F.CrtYd" user "Package Geometry/Place Bound Top")
		(29 "B.CrtYd" user "Package Geometry/Place Bound Bottom")
		(35 "F.Fab" user "Ref Des/Assembly Top")
		(33 "B.Fab" user "Ref Des/Assembly Bottom")
	)
	(footprint ""
		(layer "F.Cu")
		(at 216.29497 -69.088)
		(property "Reference" "R16"
			(at 0 0 0)
			(layer "F.SilkS")
			(hide yes)
			(effects
				(font
					(size 1.27 1.27)
				)
			)
		)
		(property "Value" "100R2F-L1-GP-U"
			(at 0.064008 -3.993896 0)
			(unlocked yes)
			(layer "F.Fab")
			(hide yes)
			(effects
				(font
					(size 1.016 1.016)
					(thickness 0.1524)
				)
			)
		)
		(property "Device Type" "R402H14"
			(at 0.064008 -5.517896 0)
			(unlocked yes)
			(layer "F.Fab")
			(hide yes)
			(effects
				(font
					(size 1.016 1.016)
					(thickness 0.1524)
				)
			)
		)
		(duplicate_pad_numbers_are_jumpers no)
		(fp_line
			(start -0.508 -0.9398)
			(end -0.508 0.9398)
			(stroke
				(width 0.1524)
				(type default)
			)
			(layer "F.SilkS")
		)
		(fp_line
			(start 0.508 -0.9398)
			(end -0.508 -0.9398)
			(stroke
				(width 0.1524)
				(type default)
			)
			(layer "F.SilkS")
		)
		(fp_rect
			(start -0.508 0.9398)
			(end 0.508 -0.9398)
			(stroke
				(width 0)
				(type default)
			)
			(fill no)
			(layer "F.CrtYd")
		)
		(fp_rect
			(start -0.508 0.9398)
			(end 0.508 -0.9398)
			(stroke
				(width 0)
				(type default)
			)
			(fill no)
			(layer "F.Fab")
		)
		(pad "1" smd custom
			(at 0 -0.4445)
			(size 0.1397 0.1397)
			(layers "F.Cu" "F.Mask" "F.Paste")
			(net "SVR_ID1")
			(options
				(clearance outline)
				(anchor circle)
			)
			(primitives
				(gr_poly
					(pts
						(arc
							(start -0.1778 -0.2794)
							(mid -0.249642 -0.249642)
							(end -0.2794 -0.1778)
						)
						(arc
							(start -0.2794 0.1778)
							(mid -0.249642 0.249642)
							(end -0.1778 0.2794)
						)
						(arc
							(start 0.1778 0.2794)
							(mid 0.249642 0.249642)
							(end 0.2794 0.1778)
						)
						(arc
							(start 0.2794 -0.1778)
							(mid 0.249642 -0.249642)
							(end 0.1778 -0.2794)
						)
					)
					(width 0)
					(fill yes)
				)
			)
		)
		(pad "2" smd custom
			(at 0 0.4445)
			(size 0.1397 0.1397)
			(layers "F.Cu" "F.Mask" "F.Paste")
			(net "GND")
			(options
				(clearance outline)
				(anchor circle)
			)
			(primitives
				(gr_poly
					(pts
						(arc
							(start -0.1778 -0.2794)
							(mid -0.249642 -0.249642)
							(end -0.2794 -0.1778)
						)
						(arc
							(start -0.2794 0.1778)
							(mid -0.249642 0.249642)
							(end -0.1778 0.2794)
						)
						(arc
							(start 0.1778 0.2794)
							(mid 0.249642 0.249642)
							(end 0.2794 0.1778)
						)
						(arc
							(start 0.2794 -0.1778)
							(mid 0.249642 -0.249642)
							(end 0.1778 -0.2794)
						)
					)
					(width 0)
					(fill yes)
				)
			)
		)
	)
	(footprint ""
		(layer "F.Cu")
		(at 195.707 -169.672 90)
		(property "Reference" "PR58"
			(at 0 0 90)
			(layer "F.SilkS")
			(hide yes)
			(effects
				(font
					(size 1.27 1.27)
				)
			)
		)
		(property "Value" "0R2J-2-GP"
			(at 0.064008 -3.993896 90)
			(unlocked yes)
			(layer "F.Fab")
			(hide yes)
			(effects
				(font
					(size 1.016 1.016)
					(thickness 0.1524)
				)
			)
		)
		(property "Device Type" "R402H16"
			(at 0.064008 -5.517896 90)
			(unlocked yes)
			(layer "F.Fab")
			(hide yes)
			(effects
				(font
					(size 1.016 1.016)
					(thickness 0.1524)
				)
			)
		)
		(duplicate_pad_numbers_are_jumpers no)
		(fp_line
			(start 0.508 -0.9398)
			(end -0.508 -0.9398)
			(stroke
				(width 0.1524)
				(type default)
			)
			(layer "F.SilkS")
		)
		(fp_line
			(start -0.508 -0.9398)
			(end -0.508 0.9398)
			(stroke
				(width 0.1524)
				(type default)
			)
			(layer "F.SilkS")
		)
		(fp_rect
			(start -0.508 0.9398)
			(end 0.508 -0.9398)
			(stroke
				(width 0)
				(type default)
			)
			(fill no)
			(layer "F.CrtYd")
		)
		(fp_rect
			(start -0.508 0.9398)
			(end 0.508 -0.9398)
			(stroke
				(width 0)
				(type default)
			)
			(fill no)
			(layer "F.Fab")
		)
		(pad "1" smd custom
			(at 0 -0.4445 90)
			(size 0.1397 0.1397)
			(layers "F.Cu" "F.Mask" "F.Paste")
			(net "P3V3_STBY_B1")
			(options
				(clearance outline)
				(anchor circle)
			)
			(primitives
				(gr_poly
					(pts
						(arc
							(start -0.1778 -0.2794)
							(mid -0.249642 -0.249642)
							(end -0.2794 -0.1778)
						)
						(arc
							(start -0.2794 0.1778)
							(mid -0.249642 0.249642)
							(end -0.1778 0.2794)
						)
						(arc
							(start 0.1778 0.2794)
							(mid 0.249642 0.249642)
							(end 0.2794 0.1778)
						)
						(arc
							(start 0.2794 -0.1778)
							(mid 0.249642 -0.249642)
							(end 0.1778 -0.2794)
						)
					)
					(width 0)
					(fill yes)
				)
			)
		)
		(pad "2" smd custom
			(at 0 0.4445 90)
			(size 0.1397 0.1397)
			(layers "F.Cu" "F.Mask" "F.Paste")
			(net "P3V3_STBY_R1")
			(options
				(clearance outline)
				(anchor circle)
			)
			(primitives
				(gr_poly
					(pts
						(arc
							(start -0.1778 -0.2794)
							(mid -0.249642 -0.249642)
							(end -0.2794 -0.1778)
						)
						(arc
							(start -0.2794 0.1778)
							(mid -0.249642 0.249642)
							(end -0.1778 0.2794)
						)
						(arc
							(start 0.1778 0.2794)
							(mid 0.249642 0.249642)
							(end 0.2794 0.1778)
						)
						(arc
							(start 0.2794 -0.1778)
							(mid 0.249642 -0.249642)
							(end 0.1778 -0.2794)
						)
					)
					(width 0)
					(fill yes)
				)
			)
		)
	)
	(footprint ""
		(layer "F.Cu")
		(at 107.88777 -72.9488 -90)
		(property "Reference" "R177"
			(at 0 0 270)
			(layer "F.SilkS")
			(hide yes)
			(effects
				(font
					(size 1.27 1.27)
				)
			)
		)
		(property "Value" "4K7R2F-GP"
			(at 0.064008 -3.993896 270)
			(unlocked yes)
			(layer "F.Fab")
			(hide yes)
			(effects
				(font
					(size 1.016 1.016)
					(thickness 0.1524)
				)
			)
		)
		(property "Device Type" "R402H16"
			(at 0.064008 -5.517896 270)
			(unlocked yes)
			(layer "F.Fab")
			(hide yes)
			(effects
				(font
					(size 1.016 1.016)
					(thickness 0.1524)
				)
			)
		)
		(duplicate_pad_numbers_are_jumpers no)
		(fp_line
			(start -0.508 -0.9398)
			(end -0.508 0.9398)
			(stroke
				(width 0.1524)
				(type default)
			)
			(layer "F.SilkS")
		)
		(fp_line
			(start 0.508 -0.9398)
			(end -0.508 -0.9398)
			(stroke
				(width 0.1524)
				(type default)
			)
			(layer "F.SilkS")
		)
		(fp_rect
			(start -0.508 0.9398)
			(end 0.508 -0.9398)
			(stroke
				(width 0)
				(type default)
			)
			(fill no)
			(layer "F.CrtYd")
		)
		(fp_rect
			(start -0.508 0.9398)
			(end 0.508 -0.9398)
			(stroke
				(width 0)
				(type default)
			)
			(fill no)
			(layer "F.Fab")
		)
		(pad "1" smd custom
			(at 0 -0.4445 270)
			(size 0.1397 0.1397)
			(layers "F.Cu" "F.Mask" "F.Paste")
			(net "TEMP_4_A1")
			(options
				(clearance outline)
				(anchor circle)
			)
			(primitives
				(gr_poly
					(pts
						(arc
							(start -0.1778 -0.2794)
							(mid -0.249642 -0.249642)
							(end -0.2794 -0.1778)
						)
						(arc
							(start -0.2794 0.1778)
							(mid -0.249642 0.249642)
							(end -0.1778 0.2794)
						)
						(arc
							(start 0.1778 0.2794)
							(mid 0.249642 0.249642)
							(end 0.2794 0.1778)
						)
						(arc
							(start 0.2794 -0.1778)
							(mid 0.249642 -0.249642)
							(end 0.1778 -0.2794)
						)
					)
					(width 0)
					(fill yes)
				)
			)
		)
		(pad "2" smd custom
			(at 0 0.4445 270)
			(size 0.1397 0.1397)
			(layers "F.Cu" "F.Mask" "F.Paste")
			(net "GND")
			(options
				(clearance outline)
				(anchor circle)
			)
			(primitives
				(gr_poly
					(pts
						(arc
							(start -0.1778 -0.2794)
							(mid -0.249642 -0.249642)
							(end -0.2794 -0.1778)
						)
						(arc
							(start -0.2794 0.1778)
							(mid -0.249642 0.249642)
							(end -0.1778 0.2794)
						)
						(arc
							(start 0.1778 0.2794)
							(mid 0.249642 0.249642)
							(end 0.2794 0.1778)
						)
						(arc
							(start 0.2794 -0.1778)
							(mid 0.249642 -0.249642)
							(end 0.1778 -0.2794)
						)
					)
					(width 0)
					(fill yes)
				)
			)
		)
	)
	(footprint ""
		(layer "F.Cu")
		(at 289.433 -163.703)
		(property "Reference" "TP139"
			(at 0 0 0)
			(layer "F.SilkS")
			(hide yes)
			(effects
				(font
					(size 1.27 1.27)
				)
			)
		)
		(property "Value" "TPAD28"
			(at 0.0127 -1.8034 0)
			(unlocked yes)
			(layer "F.Fab")
			(hide yes)
			(effects
				(font
					(size 1.016 1.016)
					(thickness 0.1524)
				)
			)
		)
		(property "Device Type" "TPAD28"
			(at 0.0127 -3.3274 0)
			(unlocked yes)
			(layer "F.Fab")
			(hide yes)
			(effects
				(font
					(size 1.016 1.016)
					(thickness 0.1524)
				)
			)
		)
		(duplicate_pad_numbers_are_jumpers no)
		(fp_poly
			(pts
				(arc
					(start 0.3556 0)
					(mid -0.3556 0)
					(end 0.3556 0)
				)
			)
			(stroke
				(width 0)
				(type default)
			)
			(fill no)
			(layer "F.CrtYd")
		)
		(fp_poly
			(pts
				(arc
					(start 0.6096 0)
					(mid -0.6096 0)
					(end 0.6096 0)
				)
			)
			(stroke
				(width 0)
				(type default)
			)
			(fill no)
			(layer "F.Fab")
		)
		(pad "1" smd circle
			(at 0 0)
			(size 0.7112 0.7112)
			(layers "F.Cu" "F.Mask" "F.Paste")
			(net "TP_BMC_GPIOE2")
		)
	)
	(footprint ""
		(layer "F.Cu")
		(at 83.420966 -87.757 180)
		(property "Reference" "SC1147"
			(at 0 0 180)
			(layer "F.SilkS")
			(hide yes)
			(effects
				(font
					(size 1.27 1.27)
				)
			)
		)
		(property "Value" "SC10U6D3V5KX-4GP"
			(at -0.0762 -6.1214 180)
			(unlocked yes)
			(layer "F.Fab")
			(hide yes)
			(effects
				(font
					(size 1.016 1.016)
					(thickness 0.1524)
				)
			)
		)
		(property "Device Type" "C805H58"
			(at -0.0762 -8.1534 180)
			(unlocked yes)
			(layer "F.Fab")
			(hide yes)
			(effects
				(font
					(size 1.016 1.016)
					(thickness 0.1524)
				)
			)
		)
		(duplicate_pad_numbers_are_jumpers no)
		(fp_line
			(start 0.635 0)
			(end -0.635 0)
			(stroke
				(width 0.508)
				(type default)
			)
			(layer "F.SilkS")
		)
		(fp_rect
			(start -0.9652 1.778)
			(end 0.9652 -1.778)
			(stroke
				(width 0)
				(type default)
			)
			(fill no)
			(layer "F.CrtYd")
		)
		(fp_poly
			(pts
				(xy -0.9652 -1.778) (xy 0.9652 -1.778) (xy 0.9652 1.778) (xy -0.9652 1.778)
			)
			(stroke
				(width 0)
				(type default)
			)
			(fill no)
			(layer "F.Fab")
		)
		(pad "1" smd rect
			(at 0 -0.9652 180)
			(size 1.397 1.143)
			(layers "F.Cu" "F.Mask" "F.Paste")
			(net "SYSPLL_VDDA18")
		)
		(pad "2" smd rect
			(at 0 0.9652 180)
			(size 1.397 1.143)
			(layers "F.Cu" "F.Mask" "F.Paste")
			(net "GND")
		)
	)
	(footprint ""
		(layer "F.Cu")
		(at 85.452966 -87.757 180)
		(property "Reference" "SC1146"
			(at 0 0 180)
			(layer "F.SilkS")
			(hide yes)
			(effects
				(font
					(size 1.27 1.27)
				)
			)
		)
		(property "Value" "SC22U6D3V5MX-2GP"
			(at -0.0762 -6.1214 180)
			(unlocked yes)
			(layer "F.Fab")
			(hide yes)
			(effects
				(font
					(size 1.016 1.016)
					(thickness 0.1524)
				)
			)
		)
		(property "Device Type" "C805H58"
			(at -0.0762 -8.1534 180)
			(unlocked yes)
			(layer "F.Fab")
			(hide yes)
			(effects
				(font
					(size 1.016 1.016)
					(thickness 0.1524)
				)
			)
		)
		(duplicate_pad_numbers_are_jumpers no)
		(fp_line
			(start 0.635 0)
			(end -0.635 0)
			(stroke
				(width 0.508)
				(type default)
			)
			(layer "F.SilkS")
		)
		(fp_rect
			(start -0.9652 1.778)
			(end 0.9652 -1.778)
			(stroke
				(width 0)
				(type default)
			)
			(fill no)
			(layer "F.CrtYd")
		)
		(fp_poly
			(pts
				(xy -0.9652 -1.778) (xy 0.9652 -1.778) (xy 0.9652 1.778) (xy -0.9652 1.778)
			)
			(stroke
				(width 0)
				(type default)
			)
			(fill no)
			(layer "F.Fab")
		)
		(pad "1" smd rect
			(at 0 -0.9652 180)
			(size 1.397 1.143)
			(layers "F.Cu" "F.Mask" "F.Paste")
			(net "SYSPLL_VDDA18")
		)
		(pad "2" smd rect
			(at 0 0.9652 180)
			(size 1.397 1.143)
			(layers "F.Cu" "F.Mask" "F.Paste")
			(net "GND")
		)
	)
	(footprint ""
		(layer "F.Cu")
		(at 261.239 -42.799 90)
		(property "Reference" "PR52"
			(at 0 0 90)
			(layer "F.SilkS")
			(hide yes)
			(effects
				(font
					(size 1.27 1.27)
				)
			)
		)
		(property "Value" "866KR2F-GP"
			(at 0.064008 -3.993896 90)
			(unlocked yes)
			(layer "F.Fab")
			(hide yes)
			(effects
				(font
					(size 1.016 1.016)
					(thickness 0.1524)
				)
			)
		)
		(property "Device Type" "R402H16"
			(at 0.064008 -5.517896 90)
			(unlocked yes)
			(layer "F.Fab")
			(hide yes)
			(effects
				(font
					(size 1.016 1.016)
					(thickness 0.1524)
				)
			)
		)
		(duplicate_pad_numbers_are_jumpers no)
		(fp_line
			(start 0.508 -0.9398)
			(end -0.508 -0.9398)
			(stroke
				(width 0.1524)
				(type default)
			)
			(layer "F.SilkS")
		)
		(fp_line
			(start -0.508 -0.9398)
			(end -0.508 0.9398)
			(stroke
				(width 0.1524)
				(type default)
			)
			(layer "F.SilkS")
		)
		(fp_rect
			(start -0.508 0.9398)
			(end 0.508 -0.9398)
			(stroke
				(width 0)
				(type default)
			)
			(fill no)
			(layer "F.CrtYd")
		)
		(fp_rect
			(start -0.508 0.9398)
			(end 0.508 -0.9398)
			(stroke
				(width 0)
				(type default)
			)
			(fill no)
			(layer "F.Fab")
		)
		(pad "1" smd custom
			(at 0 -0.4445 90)
			(size 0.1397 0.1397)
			(layers "F.Cu" "F.Mask" "F.Paste")
			(net "P1V8_STBY_VREG")
			(options
				(clearance outline)
				(anchor circle)
			)
			(primitives
				(gr_poly
					(pts
						(arc
							(start -0.1778 -0.2794)
							(mid -0.249642 -0.249642)
							(end -0.2794 -0.1778)
						)
						(arc
							(start -0.2794 0.1778)
							(mid -0.249642 0.249642)
							(end -0.1778 0.2794)
						)
						(arc
							(start 0.1778 0.2794)
							(mid 0.249642 0.249642)
							(end 0.2794 0.1778)
						)
						(arc
							(start 0.2794 -0.1778)
							(mid 0.249642 -0.249642)
							(end 0.1778 -0.2794)
						)
					)
					(width 0)
					(fill yes)
				)
			)
		)
		(pad "2" smd custom
			(at 0 0.4445 90)
			(size 0.1397 0.1397)
			(layers "F.Cu" "F.Mask" "F.Paste")
			(net "P1V8_STBY_RF")
			(options
				(clearance outline)
				(anchor circle)
			)
			(primitives
				(gr_poly
					(pts
						(arc
							(start -0.1778 -0.2794)
							(mid -0.249642 -0.249642)
							(end -0.2794 -0.1778)
						)
						(arc
							(start -0.2794 0.1778)
							(mid -0.249642 0.249642)
							(end -0.1778 0.2794)
						)
						(arc
							(start 0.1778 0.2794)
							(mid 0.249642 0.249642)
							(end 0.2794 0.1778)
						)
						(arc
							(start 0.2794 -0.1778)
							(mid 0.249642 -0.249642)
							(end 0.1778 -0.2794)
						)
					)
					(width 0)
					(fill yes)
				)
			)
		)
	)
	(footprint ""
		(layer "F.Cu")
		(at 346.612718 -157.838648 180)
		(property "Reference" "C166"
			(at 0 0 180)
			(layer "F.SilkS")
			(hide yes)
			(effects
				(font
					(size 1.27 1.27)
				)
			)
		)
		(property "Value" "SC1U10V2KX-4-GP"
			(at 1.1811 -2.7051 180)
			(unlocked yes)
			(layer "F.Fab")
			(hide yes)
			(effects
				(font
					(size 1.016 1.016)
					(thickness 0.1524)
				)
			)
		)
		(property "Device Type" "C402H22"
			(at 1.1811 -4.2291 180)
			(unlocked yes)
			(layer "F.Fab")
			(hide yes)
			(effects
				(font
					(size 1.016 1.016)
					(thickness 0.1524)
				)
			)
		)
		(duplicate_pad_numbers_are_jumpers no)
		(fp_rect
			(start -0.4318 0.9525)
			(end 0.4318 -0.9525)
			(stroke
				(width 0)
				(type default)
			)
			(fill no)
			(layer "F.CrtYd")
		)
		(fp_rect
			(start -0.4318 0.9525)
			(end 0.4318 -0.9525)
			(stroke
				(width 0)
				(type default)
			)
			(fill no)
			(layer "F.Fab")
		)
		(pad "1" smd custom
			(at 0 -0.4445 180)
			(size 0.1524 0.1524)
			(layers "F.Cu" "F.Mask" "F.Paste")
			(net "P3V3_STBY")
			(options
				(clearance outline)
				(anchor circle)
			)
			(primitives
				(gr_poly
					(pts
						(arc
							(start 0.3048 -0.2032)
							(mid 0.275042 -0.275042)
							(end 0.2032 -0.3048)
						)
						(arc
							(start -0.2032 -0.3048)
							(mid -0.275042 -0.275042)
							(end -0.3048 -0.2032)
						)
						(arc
							(start -0.3048 0.2032)
							(mid -0.275042 0.275042)
							(end -0.2032 0.3048)
						)
						(arc
							(start 0.2032 0.3048)
							(mid 0.275042 0.275042)
							(end 0.3048 0.2032)
						)
					)
					(width 0)
					(fill yes)
				)
			)
		)
		(pad "2" smd custom
			(at 0 0.4445 180)
			(size 0.1524 0.1524)
			(layers "F.Cu" "F.Mask" "F.Paste")
			(net "GND")
			(options
				(clearance outline)
				(anchor circle)
			)
			(primitives
				(gr_poly
					(pts
						(arc
							(start 0.3048 -0.2032)
							(mid 0.275042 -0.275042)
							(end 0.2032 -0.3048)
						)
						(arc
							(start -0.2032 -0.3048)
							(mid -0.275042 -0.275042)
							(end -0.3048 -0.2032)
						)
						(arc
							(start -0.3048 0.2032)
							(mid -0.275042 0.275042)
							(end -0.2032 0.3048)
						)
						(arc
							(start 0.2032 0.3048)
							(mid 0.275042 0.275042)
							(end 0.3048 0.2032)
						)
					)
					(width 0)
					(fill yes)
				)
			)
		)
	)
	(footprint ""
		(layer "F.Cu")
		(at 274.193 -185.547 90)
		(property "Reference" "R366"
			(at 0 0 90)
			(layer "F.SilkS")
			(hide yes)
			(effects
				(font
					(size 1.27 1.27)
				)
			)
		)
		(property "Value" "3K3R2F-2-GP"
			(at 0.064008 -3.993896 90)
			(unlocked yes)
			(layer "F.Fab")
			(hide yes)
			(effects
				(font
					(size 1.016 1.016)
					(thickness 0.1524)
				)
			)
		)
		(property "Device Type" "R402H16"
			(at 0.064008 -5.517896 90)
			(unlocked yes)
			(layer "F.Fab")
			(hide yes)
			(effects
				(font
					(size 1.016 1.016)
					(thickness 0.1524)
				)
			)
		)
		(duplicate_pad_numbers_are_jumpers no)
		(fp_line
			(start 0.508 -0.9398)
			(end -0.508 -0.9398)
			(stroke
				(width 0.1524)
				(type default)
			)
			(layer "F.SilkS")
		)
		(fp_line
			(start -0.508 -0.9398)
			(end -0.508 0.9398)
			(stroke
				(width 0.1524)
				(type default)
			)
			(layer "F.SilkS")
		)
		(fp_rect
			(start -0.508 0.9398)
			(end 0.508 -0.9398)
			(stroke
				(width 0)
				(type default)
			)
			(fill no)
			(layer "F.CrtYd")
		)
		(fp_rect
			(start -0.508 0.9398)
			(end 0.508 -0.9398)
			(stroke
				(width 0)
				(type default)
			)
			(fill no)
			(layer "F.Fab")
		)
		(pad "1" smd custom
			(at 0 -0.4445 90)
			(size 0.1397 0.1397)
			(layers "F.Cu" "F.Mask" "F.Paste")
			(net "P3V3_STBY")
			(options
				(clearance outline)
				(anchor circle)
			)
			(primitives
				(gr_poly
					(pts
						(arc
							(start -0.1778 -0.2794)
							(mid -0.249642 -0.249642)
							(end -0.2794 -0.1778)
						)
						(arc
							(start -0.2794 0.1778)
							(mid -0.249642 0.249642)
							(end -0.1778 0.2794)
						)
						(arc
							(start 0.1778 0.2794)
							(mid 0.249642 0.249642)
							(end 0.2794 0.1778)
						)
						(arc
							(start 0.2794 -0.1778)
							(mid 0.249642 -0.249642)
							(end 0.1778 -0.2794)
						)
					)
					(width 0)
					(fill yes)
				)
			)
		)
		(pad "2" smd custom
			(at 0 0.4445 90)
			(size 0.1397 0.1397)
			(layers "F.Cu" "F.Mask" "F.Paste")
			(net "ROMD6")
			(options
				(clearance outline)
				(anchor circle)
			)
			(primitives
				(gr_poly
					(pts
						(arc
							(start -0.1778 -0.2794)
							(mid -0.249642 -0.249642)
							(end -0.2794 -0.1778)
						)
						(arc
							(start -0.2794 0.1778)
							(mid -0.249642 0.249642)
							(end -0.1778 0.2794)
						)
						(arc
							(start 0.1778 0.2794)
							(mid 0.249642 0.249642)
							(end 0.2794 0.1778)
						)
						(arc
							(start 0.2794 -0.1778)
							(mid 0.249642 -0.249642)
							(end 0.1778 -0.2794)
						)
					)
					(width 0)
					(fill yes)
				)
			)
		)
	)
)
